(kicad_pcb
	(version 20241229)
	(generator "pcbnew")
	(generator_version "9.0")
	(general
		(thickness 1.62)
		(legacy_teardrops no)
	)
	(paper "A4")
	(title_block
		(title "OCuLink to 10GbE adapter")
		(date "2026-02-23")
		(rev "1.1.0")
		(company "Antmicro Ltd")
		(comment 1 "www.antmicro.com")
		(comment 9 "footprints 142-146 of 510")
	)
	(layers
		(0 "F.Cu" signal)
		(4 "In1.Cu" signal)
		(6 "In2.Cu" signal)
		(8 "In3.Cu" signal)
		(10 "In4.Cu" signal)
		(12 "In5.Cu" signal)
		(14 "In6.Cu" signal)
		(2 "B.Cu" signal)
		(9 "F.Adhes" user "F.Adhesive")
		(11 "B.Adhes" user "B.Adhesive")
		(13 "F.Paste" user)
		(15 "B.Paste" user)
		(5 "F.SilkS" user "F.Silkscreen")
		(7 "B.SilkS" user "B.Silkscreen")
		(1 "F.Mask" user)
		(3 "B.Mask" user)
		(17 "Dwgs.User" user "User.Drawings")
		(19 "Cmts.User" user "User.Comments")
		(21 "Eco1.User" user "User.Eco1")
		(23 "Eco2.User" user "User.Eco2")
		(25 "Edge.Cuts" user)
		(27 "Margin" user)
		(31 "F.CrtYd" user "F.Courtyard")
		(29 "B.CrtYd" user "B.Courtyard")
		(35 "F.Fab" user)
		(33 "B.Fab" user)
	)
	(footprint "antmicro-footprints:C_0402_1005Metric"
		(layer "F.Cu")
		(at 54.4 103.900001 -90)
		(descr "Capacitor SMD 0402")
		(tags "capacitor SMD 0402")
		(property "Reference" "C23"
			(at 1.259999 1.68 90)
			(layer "F.SilkS")
			(effects
				(font
					(size 0.7 0.7)
					(thickness 0.15)
				)
				(justify right top)
			)
		)
		(property "Value" "C_100n_0402"
			(at -1.022927 2.155213 90)
			(layer "F.Fab")
			(hide yes)
			(effects
				(font
					(size 0.7 0.7)
					(thickness 0.15)
				)
				(justify right top)
			)
		)
		(property "Datasheet" "https://www.murata.com/products/productdetail?partno=GRM155R61H104KE14%23"
			(at 0 0 90)
			(layer "F.Fab")
			(hide yes)
			(effects
				(font
					(size 1.27 1.27)
					(thickness 0.15)
				)
			)
		)
		(property "Description" "SMD Multilayer Ceramic Capacitor, 0.1 µF, 50 V, 0402 [1005 Metric], ± 10%, X5R, GRM Series"
			(at 0 0 90)
			(layer "F.Fab")
			(hide yes)
			(effects
				(font
					(size 1.27 1.27)
					(thickness 0.15)
				)
			)
		)
		(property "MPN" "GRM155R61H104KE14D"
			(at 0 0 270)
			(unlocked yes)
			(layer "F.Fab")
			(hide yes)
			(effects
				(font
					(size 1 1)
					(thickness 0.15)
				)
			)
		)
		(property "Manufacturer" "Murata"
			(at 0 0 270)
			(unlocked yes)
			(layer "F.Fab")
			(hide yes)
			(effects
				(font
					(size 1 1)
					(thickness 0.15)
				)
			)
		)
		(property "License" "Apache-2.0"
			(at 0 0 270)
			(unlocked yes)
			(layer "F.Fab")
			(hide yes)
			(effects
				(font
					(size 1 1)
					(thickness 0.15)
				)
			)
		)
		(property "Author" "Antmicro"
			(at 0 0 270)
			(unlocked yes)
			(layer "F.Fab")
			(hide yes)
			(effects
				(font
					(size 1 1)
					(thickness 0.15)
				)
			)
		)
		(property "Val" "100n"
			(at 0 0 270)
			(unlocked yes)
			(layer "F.Fab")
			(hide yes)
			(effects
				(font
					(size 1 1)
					(thickness 0.15)
				)
			)
		)
		(property "Voltage" "50V"
			(at 0 0 270)
			(unlocked yes)
			(layer "F.Fab")
			(hide yes)
			(effects
				(font
					(size 1 1)
					(thickness 0.15)
				)
			)
		)
		(property "Dielectric" "X5R"
			(at 0 0 270)
			(unlocked yes)
			(layer "F.Fab")
			(hide yes)
			(effects
				(font
					(size 1 1)
					(thickness 0.15)
				)
			)
		)
		(sheetname "/Power/")
		(sheetfile "power.kicad_sch")
		(attr smd)
		(fp_rect
			(start -0.925 -0.47)
			(end 0.925 0.47)
			(stroke
				(width 0.05)
				(type default)
			)
			(fill no)
			(layer "F.CrtYd")
		)
		(fp_line
			(start -0.494 0.248)
			(end -0.494 -0.25)
			(stroke
				(width 0.15)
				(type solid)
			)
			(layer "F.Fab")
		)
		(fp_line
			(start 0.504 0.248)
			(end -0.494 0.248)
			(stroke
				(width 0.15)
				(type solid)
			)
			(layer "F.Fab")
		)
		(fp_line
			(start -0.494 -0.25)
			(end 0.504 -0.25)
			(stroke
				(width 0.15)
				(type solid)
			)
			(layer "F.Fab")
		)
		(fp_line
			(start 0.504 -0.25)
			(end 0.504 0.248)
			(stroke
				(width 0.15)
				(type solid)
			)
			(layer "F.Fab")
		)
		(pad "1" smd roundrect
			(at -0.48 0 270)
			(size 0.59 0.64)
			(layers "F.Cu" "F.Mask" "F.Paste")
			(roundrect_rratio 0.25)
			(net 28 "GND")
			(pintype "passive")
		)
		(pad "2" smd roundrect
			(at 0.48 0 270)
			(size 0.59 0.64)
			(layers "F.Cu" "F.Mask" "F.Paste")
			(roundrect_rratio 0.25)
			(net 314 "VCC")
			(pintype "passive")
		)
	)
	(footprint "antmicro-footprints:C_0603_1608Metric_EIA"
		(layer "F.Cu")
		(at 73.549998 83.909996 -90)
		(descr "Capacitor SMD 0603, IPC-7351 Density Level A")
		(tags "Capacitor 0603")
		(property "Reference" "C7"
			(at 1.830004 1.529998 90)
			(layer "F.SilkS")
			(effects
				(font
					(size 0.7 0.7)
					(thickness 0.15)
				)
				(justify right top)
			)
		)
		(property "Value" "C_22u_16V_0603"
			(at -1.42757 1.770288 90)
			(layer "F.Fab")
			(hide yes)
			(effects
				(font
					(size 0.7 0.7)
					(thickness 0.15)
				)
				(justify right top)
			)
		)
		(property "Datasheet" "https://product.samsungsem.com/mlcc/CL10A226MO7JZN.do"
			(at 0 0 90)
			(layer "F.Fab")
			(hide yes)
			(effects
				(font
					(size 1.27 1.27)
					(thickness 0.15)
				)
			)
		)
		(property "Description" "SMD Multilayer Ceramic Capacitor"
			(at 0 0 90)
			(layer "F.Fab")
			(hide yes)
			(effects
				(font
					(size 1.27 1.27)
					(thickness 0.15)
				)
			)
		)
		(property "MPN" "CL10A226MO7JZNC"
			(at 0 0 270)
			(unlocked yes)
			(layer "F.Fab")
			(hide yes)
			(effects
				(font
					(size 1 1)
					(thickness 0.15)
				)
			)
		)
		(property "Manufacturer" "Samsung Electro-Mechanics"
			(at 0 0 270)
			(unlocked yes)
			(layer "F.Fab")
			(hide yes)
			(effects
				(font
					(size 1 1)
					(thickness 0.15)
				)
			)
		)
		(property "License" "Apache-2.0"
			(at 0 0 270)
			(unlocked yes)
			(layer "F.Fab")
			(hide yes)
			(effects
				(font
					(size 1 1)
					(thickness 0.15)
				)
			)
		)
		(property "Author" "Antmicro"
			(at 0 0 270)
			(unlocked yes)
			(layer "F.Fab")
			(hide yes)
			(effects
				(font
					(size 1 1)
					(thickness 0.15)
				)
			)
		)
		(property "Val" "22u"
			(at 0 0 270)
			(unlocked yes)
			(layer "F.Fab")
			(hide yes)
			(effects
				(font
					(size 1 1)
					(thickness 0.15)
				)
			)
		)
		(property "Voltage" "16V"
			(at 0 0 270)
			(unlocked yes)
			(layer "F.Fab")
			(hide yes)
			(effects
				(font
					(size 1 1)
					(thickness 0.15)
				)
			)
		)
		(property "Dielectric" ""
			(at 0 0 270)
			(unlocked yes)
			(layer "F.Fab")
			(hide yes)
			(effects
				(font
					(size 1 1)
					(thickness 0.15)
				)
			)
		)
		(property "Public" "False"
			(at 0 0 270)
			(unlocked yes)
			(layer "F.Fab")
			(hide yes)
			(effects
				(font
					(size 1 1)
					(thickness 0.15)
				)
			)
		)
		(sheetname "/Power/")
		(sheetfile "power.kicad_sch")
		(attr smd)
		(fp_line
			(start -0.15 0.55)
			(end 0.15 0.55)
			(stroke
				(width 0.15)
				(type solid)
			)
			(layer "F.SilkS")
		)
		(fp_line
			(start -0.15 -0.55)
			(end 0.15 -0.55)
			(stroke
				(width 0.15)
				(type solid)
			)
			(layer "F.SilkS")
		)
		(fp_rect
			(start -1.25 -0.65)
			(end 1.25 0.65)
			(stroke
				(width 0.05)
				(type solid)
			)
			(fill no)
			(layer "F.CrtYd")
		)
		(fp_rect
			(start -0.8 -0.45)
			(end 0.8 0.45)
			(stroke
				(width 0.15)
				(type solid)
			)
			(fill no)
			(layer "F.Fab")
		)
		(pad "1" smd roundrect
			(at -0.7 0 270)
			(size 0.8 1.1)
			(layers "F.Cu" "F.Mask" "F.Paste")
			(roundrect_rratio 0.2)
			(net 28 "GND")
			(pintype "passive")
		)
		(pad "2" smd roundrect
			(at 0.7 0 270)
			(size 0.8 1.1)
			(layers "F.Cu" "F.Mask" "F.Paste")
			(roundrect_rratio 0.2)
			(net 255 "/Power/+3V3_OUT")
			(pintype "passive")
		)
	)
	(footprint "antmicro-footprints:R_0402_1005Metric"
		(layer "F.Cu")
		(at 97.4 104.25)
		(descr "Resistor SMD 0402")
		(tags "resistor SMD 0402")
		(property "Reference" "R98"
			(at -2.25 15.175 0)
			(layer "F.SilkS")
			(effects
				(font
					(size 0.7 0.7)
					(thickness 0.15)
				)
				(justify left bottom)
			)
		)
		(property "Value" "R_10k_0402"
			(at -1.011843 1.772047 0)
			(layer "F.Fab")
			(hide yes)
			(effects
				(font
					(size 0.7 0.7)
					(thickness 0.15)
				)
				(justify left bottom)
			)
		)
		(property "Datasheet" "https://www.bourns.com/docs/product-datasheets/cr.pdf"
			(at 0 0 0)
			(layer "F.Fab")
			(hide yes)
			(effects
				(font
					(size 1.27 1.27)
					(thickness 0.15)
				)
			)
		)
		(property "Description" "SMD Chip Resistor, 10 kohm, ± 1%, 62.5 mW, 0402 [1005 Metric], Thick Film, General Purpose"
			(at 0 0 0)
			(layer "F.Fab")
			(hide yes)
			(effects
				(font
					(size 1.27 1.27)
					(thickness 0.15)
				)
			)
		)
		(property "MPN" "CR0402-FX-1002GLF"
			(at 0 0 0)
			(unlocked yes)
			(layer "F.Fab")
			(hide yes)
			(effects
				(font
					(size 1 1)
					(thickness 0.15)
				)
			)
		)
		(property "Manufacturer" "Bourns"
			(at 0 0 0)
			(unlocked yes)
			(layer "F.Fab")
			(hide yes)
			(effects
				(font
					(size 1 1)
					(thickness 0.15)
				)
			)
		)
		(property "License" "Apache-2.0"
			(at 0 0 0)
			(unlocked yes)
			(layer "F.Fab")
			(hide yes)
			(effects
				(font
					(size 1 1)
					(thickness 0.15)
				)
			)
		)
		(property "Author" "Antmicro"
			(at 0 0 0)
			(unlocked yes)
			(layer "F.Fab")
			(hide yes)
			(effects
				(font
					(size 1 1)
					(thickness 0.15)
				)
			)
		)
		(property "Val" "10k"
			(at 0 0 0)
			(unlocked yes)
			(layer "F.Fab")
			(hide yes)
			(effects
				(font
					(size 1 1)
					(thickness 0.15)
				)
			)
		)
		(property "Tolerance" "1%"
			(at 0 0 0)
			(unlocked yes)
			(layer "F.Fab")
			(hide yes)
			(effects
				(font
					(size 1 1)
					(thickness 0.15)
				)
			)
		)
		(sheetname "/X710-AT2 Misc/")
		(sheetfile "x710-at2-mics.kicad_sch")
		(attr smd)
		(fp_rect
			(start -0.925 -0.47)
			(end 0.925 0.47)
			(stroke
				(width 0.05)
				(type default)
			)
			(fill no)
			(layer "F.CrtYd")
		)
		(fp_rect
			(start -0.5 -0.25)
			(end 0.5 0.25)
			(stroke
				(width 0.15)
				(type solid)
			)
			(fill no)
			(layer "F.Fab")
		)
		(pad "1" smd roundrect
			(at -0.48 0)
			(size 0.59 0.64)
			(layers "F.Cu" "F.Mask" "F.Paste")
			(roundrect_rratio 0.25)
			(net 100 "/X710-AT2 Misc/AUX_PWR")
			(pintype "passive")
		)
		(pad "2" smd roundrect
			(at 0.48 0)
			(size 0.59 0.64)
			(layers "F.Cu" "F.Mask" "F.Paste")
			(roundrect_rratio 0.25)
			(net 7 "+3V3")
			(pintype "passive")
		)
	)
	(footprint "antmicro-footprints:LED_0603_1608Metric_G"
		(layer "F.Cu")
		(at 54.35 125.1 180)
		(descr "LED SMD 0603 Green")
		(tags "LED SMD 0603 Green")
		(property "Reference" "D17"
			(at -1.1 -0.75 0)
			(layer "F.SilkS")
			(effects
				(font
					(size 0.7 0.7)
					(thickness 0.15)
				)
				(justify right top)
			)
		)
		(property "Value" "LED_G_0603_LG_L29K-G2J1-24-Z"
			(at -0.001 1.599 0)
			(layer "F.Fab")
			(hide yes)
			(effects
				(font
					(size 0.7 0.7)
					(thickness 0.15)
				)
				(justify right top)
			)
		)
		(property "Datasheet" "https://look.ams-osram.com/m/19ee86b3ae0ee95b/original/LG-L29K.pdf"
			(at 0 0 0)
			(layer "F.Fab")
			(hide yes)
			(effects
				(font
					(size 1.27 1.27)
					(thickness 0.15)
				)
			)
		)
		(property "Description" "LED, Green, SMD, 0603, 20 mA, 1.7 V, 570 nm"
			(at 0 0 0)
			(layer "F.Fab")
			(hide yes)
			(effects
				(font
					(size 1.27 1.27)
					(thickness 0.15)
				)
			)
		)
		(property "MPN" "LG L29K-G2J1-24-Z"
			(at 0 0 180)
			(unlocked yes)
			(layer "F.Fab")
			(hide yes)
			(effects
				(font
					(size 1 1)
					(thickness 0.15)
				)
			)
		)
		(property "Manufacturer" "OSRAM"
			(at 0 0 180)
			(unlocked yes)
			(layer "F.Fab")
			(hide yes)
			(effects
				(font
					(size 1 1)
					(thickness 0.15)
				)
			)
		)
		(property "Color" "Green"
			(at 0 0 180)
			(unlocked yes)
			(layer "F.Fab")
			(hide yes)
			(effects
				(font
					(size 1 1)
					(thickness 0.15)
				)
			)
		)
		(property "Author" "Antmicro"
			(at 0 0 180)
			(unlocked yes)
			(layer "F.Fab")
			(hide yes)
			(effects
				(font
					(size 1 1)
					(thickness 0.15)
				)
			)
		)
		(property "License" "Apache-2.0"
			(at 0 0 180)
			(unlocked yes)
			(layer "F.Fab")
			(hide yes)
			(effects
				(font
					(size 1 1)
					(thickness 0.15)
				)
			)
		)
		(sheetname "/Power/")
		(sheetfile "power.kicad_sch")
		(attr smd)
		(fp_line
			(start 0.22 0.35)
			(end -0.22 0.35)
			(stroke
				(width 0.15)
				(type solid)
			)
			(layer "F.SilkS")
		)
		(fp_line
			(start 0.22 -0.35)
			(end -0.22 -0.35)
			(stroke
				(width 0.15)
				(type solid)
			)
			(layer "F.SilkS")
		)
		(fp_line
			(start 0.105328 0.201008)
			(end 0.105328 -0.198992)
			(stroke
				(width 0.1)
				(type solid)
			)
			(layer "F.SilkS")
		)
		(fp_line
			(start 0.105328 0.201008)
			(end -0.094672 0.001008)
			(stroke
				(width 0.1)
				(type solid)
			)
			(layer "F.SilkS")
		)
		(fp_line
			(start 0.105328 0.001008)
			(end 0.24 0.001)
			(stroke
				(width 0.1)
				(type solid)
			)
			(layer "F.SilkS")
		)
		(fp_line
			(start -0.094672 0.201008)
			(end -0.094672 -0.198992)
			(stroke
				(width 0.1)
				(type solid)
			)
			(layer "F.SilkS")
		)
		(fp_line
			(start -0.094672 0.001008)
			(end 0.105328 -0.198992)
			(stroke
				(width 0.1)
				(type solid)
			)
			(layer "F.SilkS")
		)
		(fp_line
			(start -0.094672 0.001008)
			(end -0.24 0.001008)
			(stroke
				(width 0.1)
				(type solid)
			)
			(layer "F.SilkS")
		)
		(fp_line
			(start -1.18 -0.319)
			(end -1.18 0.321)
			(stroke
				(width 0.15)
				(type solid)
			)
			(layer "F.SilkS")
		)
		(fp_rect
			(start 1.25 0.65)
			(end -1.25 -0.65)
			(stroke
				(width 0.05)
				(type solid)
			)
			(fill no)
			(layer "F.CrtYd")
		)
		(fp_line
			(start 0.599 0)
			(end 0.201 0)
			(stroke
				(width 0.15)
				(type solid)
			)
			(layer "F.Fab")
		)
		(fp_line
			(start 0.201 0.2)
			(end 0.201 0)
			(stroke
				(width 0.15)
				(type solid)
			)
			(layer "F.Fab")
		)
		(fp_line
			(start 0.201 0)
			(end 0.201 -0.202)
			(stroke
				(width 0.15)
				(type solid)
			)
			(layer "F.Fab")
		)
		(fp_line
			(start 0.201 -0.202)
			(end -0.101 0)
			(stroke
				(width 0.15)
				(type solid)
			)
			(layer "F.Fab")
		)
		(fp_line
			(start -0.101 0)
			(end 0.201 0.2)
			(stroke
				(width 0.15)
				(type solid)
			)
			(layer "F.Fab")
		)
		(fp_line
			(start -0.199 0.2)
			(end -0.199 0.1)
			(stroke
				(width 0.15)
				(type solid)
			)
			(layer "F.Fab")
		)
		(fp_line
			(start -0.199 0)
			(end -0.597 0)
			(stroke
				(width 0.15)
				(type solid)
			)
			(layer "F.Fab")
		)
		(fp_line
			(start -0.199 -0.202)
			(end -0.199 0.1)
			(stroke
				(width 0.15)
				(type solid)
			)
			(layer "F.Fab")
		)
		(fp_rect
			(start 0.848 0.4)
			(end -0.85 -0.402)
			(stroke
				(width 0.15)
				(type solid)
			)
			(fill no)
			(layer "F.Fab")
		)
		(fp_text user "Author: Antmicro"
			(at -1.4224 4.799 180)
			(layer "F.Fab")
			(effects
				(font
					(size 0.7 0.7)
					(thickness 0.15)
				)
				(justify left bottom)
			)
		)
		(fp_text user "License: Apache-2.0"
			(at -1.4224 3.599 180)
			(layer "F.Fab")
			(effects
				(font
					(size 0.7 0.7)
					(thickness 0.15)
				)
				(justify left bottom)
			)
		)
		(fp_text user "${REFERENCE}"
			(at -1.4224 5.999 180)
			(layer "F.Fab")
			(effects
				(font
					(size 0.7 0.7)
					(thickness 0.15)
				)
				(justify left bottom)
			)
		)
		(pad "1" smd roundrect
			(at -0.7 0)
			(size 0.8 1)
			(layers "F.Cu" "F.Mask" "F.Paste")
			(roundrect_rratio 0.2)
			(net 411 "Net-(D17-C)")
			(pinfunction "C")
			(pintype "passive")
		)
		(pad "2" smd roundrect
			(at 0.7 0)
			(size 0.8 1)
			(layers "F.Cu" "F.Mask" "F.Paste")
			(roundrect_rratio 0.2)
			(net 255 "/Power/+3V3_OUT")
			(pinfunction "A")
			(pintype "passive")
		)
	)
	(footprint "antmicro-footprints:FB_0603_1608Metric"
		(layer "F.Cu")
		(at 69.1 97.75)
		(property "Reference" "FB4"
			(at -3.19 0.41 0)
			(layer "F.SilkS")
			(effects
				(font
					(size 0.7 0.7)
					(thickness 0.15)
				)
				(justify left bottom)
			)
		)
		(property "Value" "FB_33Z_3A_Murata-BLM18PG_0603"
			(at 0 1.5 0)
			(layer "F.Fab")
			(hide yes)
			(effects
				(font
					(size 0.7 0.7)
					(thickness 0.15)
				)
				(justify left bottom)
			)
		)
		(property "Datasheet" "https://www.murata.com/products/productdata/8796737273886/QNFA9101.pdf?1649080818000"
			(at 0 0 0)
			(layer "F.Fab")
			(hide yes)
			(effects
				(font
					(size 1.27 1.27)
					(thickness 0.15)
				)
			)
		)
		(property "Description" "Ferrite Bead, 0603 [1608 Metric], 33 ohm, 3 A, BLM18PG, 0.025 ohm, ± 25%, DC power line"
			(at 0 0 0)
			(layer "F.Fab")
			(hide yes)
			(effects
				(font
					(size 1.27 1.27)
					(thickness 0.15)
				)
			)
		)
		(property "Val" "33Z/3A"
			(at 0 0 0)
			(unlocked yes)
			(layer "F.Fab")
			(hide yes)
			(effects
				(font
					(size 1 1)
					(thickness 0.15)
				)
			)
		)
		(property "MPN" "BLM18PG330SH1D"
			(at 0 0 0)
			(unlocked yes)
			(layer "F.Fab")
			(hide yes)
			(effects
				(font
					(size 1 1)
					(thickness 0.15)
				)
			)
		)
		(property "Manufacturer" "Murata"
			(at 0 0 0)
			(unlocked yes)
			(layer "F.Fab")
			(hide yes)
			(effects
				(font
					(size 1 1)
					(thickness 0.15)
				)
			)
		)
		(property "Current" ""
			(at 0 0 0)
			(unlocked yes)
			(layer "F.Fab")
			(hide yes)
			(effects
				(font
					(size 1 1)
					(thickness 0.15)
				)
			)
		)
		(property "Author" "Antmicro"
			(at 0 0 0)
			(unlocked yes)
			(layer "F.Fab")
			(hide yes)
			(effects
				(font
					(size 1 1)
					(thickness 0.15)
				)
			)
		)
		(property "License" "Apache-2.0"
			(at 0 0 0)
			(unlocked yes)
			(layer "F.Fab")
			(hide yes)
			(effects
				(font
					(size 1 1)
					(thickness 0.15)
				)
			)
		)
		(sheetname "/X710-AT2 power/")
		(sheetfile "x710-at2-power.kicad_sch")
		(attr smd)
		(fp_line
			(start -0.15 -0.4)
			(end 0.15 -0.4)
			(stroke
				(width 0.15)
				(type solid)
			)
			(layer "F.SilkS")
		)
		(fp_line
			(start -0.15 0.4)
			(end 0.15 0.4)
			(stroke
				(width 0.15)
				(type solid)
			)
			(layer "F.SilkS")
		)
		(fp_rect
			(start -1.25 -0.65)
			(end 1.25 0.65)
			(stroke
				(width 0.05)
				(type solid)
			)
			(fill no)
			(layer "F.CrtYd")
		)
		(fp_line
			(start -0.803 0.406)
			(end -0.803 -0.408)
			(stroke
				(width 0.15)
				(type solid)
			)
			(layer "F.Fab")
		)
		(fp_line
			(start 0.8 -0.408)
			(end -0.803 -0.408)
			(stroke
				(width 0.15)
				(type solid)
			)
			(layer "F.Fab")
		)
		(fp_line
			(start 0.8 -0.408)
			(end 0.8 0.406)
			(stroke
				(width 0.15)
				(type solid)
			)
			(layer "F.Fab")
		)
		(fp_line
			(start 0.8 0.406)
			(end -0.803 0.406)
			(stroke
				(width 0.15)
				(type solid)
			)
			(layer "F.Fab")
		)
		(pad "1" smd roundrect
			(at -0.7 0)
			(size 0.8 1)
			(layers "F.Cu" "F.Mask" "F.Paste")
			(roundrect_rratio 0.2)
			(net 18 "+1V88")
			(pintype "passive")
		)
		(pad "2" smd roundrect
			(at 0.7 0)
			(size 0.8 1)
			(layers "F.Cu" "F.Mask" "F.Paste")
			(roundrect_rratio 0.2)
			(net 10 "AVDDH")
			(pintype "passive")
		)
	)
)
